(kicad_pcb
	(version 20260206)
	(generator "pcbnew")
	(generator_version "10.0")
	(general
		(thickness 1.6)
		(legacy_teardrops no)
	)
	(paper "A4")
	(title_block
		(title "Bryce Canyon_F.DPB_16315-1-OCP.brd")
		(comment 1 "Bryce Canyon / footprints 1109-1115 of 2223")
	)
	(layers
		(0 "F.Cu" signal "TOP")
		(4 "In1.Cu" signal "L2GND")
		(6 "In2.Cu" signal "L3")
		(8 "In3.Cu" signal "L4GND")
		(10 "In4.Cu" signal "L5")
		(12 "In5.Cu" signal "L6VCC")
		(14 "In6.Cu" signal "L7VCC")
		(16 "In7.Cu" signal "L8")
		(18 "In8.Cu" signal "L9GND")
		(20 "In9.Cu" signal "L10")
		(22 "In10.Cu" signal "L11GND")
		(2 "B.Cu" signal "BOTTOM")
		(9 "F.Adhes" user "F.Adhesive")
		(11 "B.Adhes" user "B.Adhesive")
		(13 "F.Paste" user "Package Geometry/Pastemask Top")
		(15 "B.Paste" user "Package Geometry/Pastemask Bottom")
		(5 "F.SilkS" user "Ref Des/Silkscreen Top")
		(7 "B.SilkS" user "Ref Des/Silkscreen Bottom")
		(1 "F.Mask" user "Board Geometry/Soldermask Top")
		(3 "B.Mask" user "Board Geometry/Soldermask Bottom")
		(17 "Dwgs.User" user "User.Drawings")
		(19 "Cmts.User" user "User.Comments")
		(21 "Eco1.User" user "User.Eco1")
		(23 "Eco2.User" user "User.Eco2")
		(25 "Edge.Cuts" user "Board Geometry/Outline")
		(27 "Margin" user)
		(31 "F.CrtYd" user "Package Geometry/Place Bound Top")
		(29 "B.CrtYd" user "Package Geometry/Place Bound Bottom")
		(35 "F.Fab" user "Ref Des/Assembly Top")
		(33 "B.Fab" user "Ref Des/Assembly Bottom")
	)
	(footprint ""
		(layer "F.Cu")
		(at 164.283136 -188.875162)
		(property "Reference" "Q232"
			(at 0 0 0)
			(layer "F.SilkS")
			(hide yes)
			(effects
				(font
					(size 1.27 1.27)
				)
			)
		)
		(property "Value" "2N7002K-2-GP"
			(at 0.127 -8.9662 0)
			(unlocked yes)
			(layer "F.Fab")
			(hide yes)
			(effects
				(font
					(size 1.016 1.016)
					(thickness 0.1524)
				)
			)
		)
		(property "Device Type" "SOT23DGS2D4H44"
			(at 0.127 -10.4902 0)
			(unlocked yes)
			(layer "F.Fab")
			(hide yes)
			(effects
				(font
					(size 1.016 1.016)
					(thickness 0.1524)
				)
			)
		)
		(duplicate_pad_numbers_are_jumpers no)
		(fp_line
			(start -1.651 -1.778)
			(end -1.651 1.778)
			(stroke
				(width 0.1524)
				(type default)
			)
			(layer "F.SilkS")
		)
		(fp_line
			(start -1.651 1.778)
			(end 1.651 1.778)
			(stroke
				(width 0.1524)
				(type default)
			)
			(layer "F.SilkS")
		)
		(fp_line
			(start 1.651 -1.778)
			(end -1.651 -1.778)
			(stroke
				(width 0.1524)
				(type default)
			)
			(layer "F.SilkS")
		)
		(fp_line
			(start 1.651 1.778)
			(end 1.651 -1.778)
			(stroke
				(width 0.1524)
				(type default)
			)
			(layer "F.SilkS")
		)
		(fp_poly
			(pts
				(xy -1.778 1.8796) (xy -1.778 -1.8796) (xy 1.778 -1.8796) (xy 1.778 1.8796)
			)
			(stroke
				(width 0)
				(type default)
			)
			(fill no)
			(layer "F.CrtYd")
		)
		(fp_poly
			(pts
				(xy -1.778 1.8796) (xy -1.778 -1.8796) (xy 1.778 -1.8796) (xy 1.778 1.8796)
			)
			(stroke
				(width 0)
				(type default)
			)
			(fill no)
			(layer "F.Fab")
		)
		(pad "D" smd custom
			(at 0 -0.9525)
			(size 0.1905 0.1905)
			(layers "F.Cu" "F.Mask" "F.Paste")
			(net "FLT_HDD5_N")
			(options
				(clearance outline)
				(anchor circle)
			)
			(primitives
				(gr_poly
					(pts
						(arc
							(start -0.1778 0.5715)
							(mid -0.321484 0.511984)
							(end -0.381 0.3683)
						)
						(arc
							(start -0.381 -0.3683)
							(mid -0.321484 -0.511984)
							(end -0.1778 -0.5715)
						)
						(arc
							(start 0.1778 -0.5715)
							(mid 0.321484 -0.511984)
							(end 0.381 -0.3683)
						)
						(arc
							(start 0.381 0.3683)
							(mid 0.321484 0.511984)
							(end 0.1778 0.5715)
						)
					)
					(width 0)
					(fill yes)
				)
			)
		)
		(pad "G" smd custom
			(at -0.98425 0.9525)
			(size 0.1905 0.1905)
			(layers "F.Cu" "F.Mask" "F.Paste")
			(net "DRIVE_A_5_FLT_LED")
			(options
				(clearance outline)
				(anchor circle)
			)
			(primitives
				(gr_poly
					(pts
						(arc
							(start -0.1778 0.5715)
							(mid -0.321484 0.511984)
							(end -0.381 0.3683)
						)
						(arc
							(start -0.381 -0.3683)
							(mid -0.321484 -0.511984)
							(end -0.1778 -0.5715)
						)
						(arc
							(start 0.1778 -0.5715)
							(mid 0.321484 -0.511984)
							(end 0.381 -0.3683)
						)
						(arc
							(start 0.381 0.3683)
							(mid 0.321484 0.511984)
							(end 0.1778 0.5715)
						)
					)
					(width 0)
					(fill yes)
				)
			)
		)
		(pad "S" smd custom
			(at 0.98425 0.9525)
			(size 0.1905 0.1905)
			(layers "F.Cu" "F.Mask" "F.Paste")
			(net "GND")
			(options
				(clearance outline)
				(anchor circle)
			)
			(primitives
				(gr_poly
					(pts
						(arc
							(start -0.1778 0.5715)
							(mid -0.321484 0.511984)
							(end -0.381 0.3683)
						)
						(arc
							(start -0.381 -0.3683)
							(mid -0.321484 -0.511984)
							(end -0.1778 -0.5715)
						)
						(arc
							(start 0.1778 -0.5715)
							(mid 0.321484 -0.511984)
							(end 0.381 -0.3683)
						)
						(arc
							(start 0.381 0.3683)
							(mid 0.321484 0.511984)
							(end 0.1778 0.5715)
						)
					)
					(width 0)
					(fill yes)
				)
			)
		)
	)
	(footprint ""
		(layer "F.Cu")
		(at 264.356342 -210.617562 180)
		(property "Reference" "R402"
			(at 0 0 180)
			(layer "F.SilkS")
			(hide yes)
			(effects
				(font
					(size 1.27 1.27)
				)
			)
		)
		(property "Value" "1KR2F-3-GP"
			(at 0.064008 -3.993896 180)
			(unlocked yes)
			(layer "F.Fab")
			(hide yes)
			(effects
				(font
					(size 1.016 1.016)
					(thickness 0.1524)
				)
			)
		)
		(property "Device Type" "R402H16"
			(at 0.064008 -5.517896 180)
			(unlocked yes)
			(layer "F.Fab")
			(hide yes)
			(effects
				(font
					(size 1.016 1.016)
					(thickness 0.1524)
				)
			)
		)
		(duplicate_pad_numbers_are_jumpers no)
		(fp_line
			(start 0.508 -0.9398)
			(end -0.508 -0.9398)
			(stroke
				(width 0.1524)
				(type default)
			)
			(layer "F.SilkS")
		)
		(fp_line
			(start -0.508 -0.9398)
			(end -0.508 0.9398)
			(stroke
				(width 0.1524)
				(type default)
			)
			(layer "F.SilkS")
		)
		(fp_rect
			(start -0.508 0.9398)
			(end 0.508 -0.9398)
			(stroke
				(width 0)
				(type default)
			)
			(fill no)
			(layer "F.CrtYd")
		)
		(fp_rect
			(start -0.508 0.9398)
			(end 0.508 -0.9398)
			(stroke
				(width 0)
				(type default)
			)
			(fill no)
			(layer "F.Fab")
		)
		(pad "1" smd custom
			(at 0 -0.4445 180)
			(size 0.1397 0.1397)
			(layers "F.Cu" "F.Mask" "F.Paste")
			(net "P3V3_STBY_A")
			(options
				(clearance outline)
				(anchor circle)
			)
			(primitives
				(gr_poly
					(pts
						(arc
							(start -0.1778 -0.2794)
							(mid -0.249642 -0.249642)
							(end -0.2794 -0.1778)
						)
						(arc
							(start -0.2794 0.1778)
							(mid -0.249642 0.249642)
							(end -0.1778 0.2794)
						)
						(arc
							(start 0.1778 0.2794)
							(mid 0.249642 0.249642)
							(end 0.2794 0.1778)
						)
						(arc
							(start 0.2794 -0.1778)
							(mid 0.249642 -0.249642)
							(end 0.1778 -0.2794)
						)
					)
					(width 0)
					(fill yes)
				)
			)
		)
		(pad "2" smd custom
			(at 0 0.4445 180)
			(size 0.1397 0.1397)
			(layers "F.Cu" "F.Mask" "F.Paste")
			(net "I2C_DPB_A_SCL_BUF")
			(options
				(clearance outline)
				(anchor circle)
			)
			(primitives
				(gr_poly
					(pts
						(arc
							(start -0.1778 -0.2794)
							(mid -0.249642 -0.249642)
							(end -0.2794 -0.1778)
						)
						(arc
							(start -0.2794 0.1778)
							(mid -0.249642 0.249642)
							(end -0.1778 0.2794)
						)
						(arc
							(start 0.1778 0.2794)
							(mid 0.249642 0.249642)
							(end 0.2794 0.1778)
						)
						(arc
							(start 0.2794 -0.1778)
							(mid 0.249642 -0.249642)
							(end 0.1778 -0.2794)
						)
					)
					(width 0)
					(fill yes)
				)
			)
		)
	)
	(footprint ""
		(layer "F.Cu")
		(at 331.359002 -22.671532)
		(property "Reference" "R986"
			(at 0 0 0)
			(layer "F.SilkS")
			(hide yes)
			(effects
				(font
					(size 1.27 1.27)
				)
			)
		)
		(property "Value" "4K7R2F-GP"
			(at 0.064008 -3.993896 0)
			(unlocked yes)
			(layer "F.Fab")
			(hide yes)
			(effects
				(font
					(size 1.016 1.016)
					(thickness 0.1524)
				)
			)
		)
		(property "Device Type" "R402H16"
			(at 0.064008 -5.517896 0)
			(unlocked yes)
			(layer "F.Fab")
			(hide yes)
			(effects
				(font
					(size 1.016 1.016)
					(thickness 0.1524)
				)
			)
		)
		(duplicate_pad_numbers_are_jumpers no)
		(fp_line
			(start -0.508 -0.9398)
			(end -0.508 0.9398)
			(stroke
				(width 0.1524)
				(type default)
			)
			(layer "F.SilkS")
		)
		(fp_line
			(start 0.508 -0.9398)
			(end -0.508 -0.9398)
			(stroke
				(width 0.1524)
				(type default)
			)
			(layer "F.SilkS")
		)
		(fp_rect
			(start -0.508 0.9398)
			(end 0.508 -0.9398)
			(stroke
				(width 0)
				(type default)
			)
			(fill no)
			(layer "F.CrtYd")
		)
		(fp_rect
			(start -0.508 0.9398)
			(end 0.508 -0.9398)
			(stroke
				(width 0)
				(type default)
			)
			(fill no)
			(layer "F.Fab")
		)
		(pad "1" smd custom
			(at 0 -0.4445)
			(size 0.1397 0.1397)
			(layers "F.Cu" "F.Mask" "F.Paste")
			(net "IOM_B_SLOT_ID_0")
			(options
				(clearance outline)
				(anchor circle)
			)
			(primitives
				(gr_poly
					(pts
						(arc
							(start -0.1778 -0.2794)
							(mid -0.249642 -0.249642)
							(end -0.2794 -0.1778)
						)
						(arc
							(start -0.2794 0.1778)
							(mid -0.249642 0.249642)
							(end -0.1778 0.2794)
						)
						(arc
							(start 0.1778 0.2794)
							(mid 0.249642 0.249642)
							(end 0.2794 0.1778)
						)
						(arc
							(start 0.2794 -0.1778)
							(mid 0.249642 -0.249642)
							(end 0.1778 -0.2794)
						)
					)
					(width 0)
					(fill yes)
				)
			)
		)
		(pad "2" smd custom
			(at 0 0.4445)
			(size 0.1397 0.1397)
			(layers "F.Cu" "F.Mask" "F.Paste")
			(net "GND")
			(options
				(clearance outline)
				(anchor circle)
			)
			(primitives
				(gr_poly
					(pts
						(arc
							(start -0.1778 -0.2794)
							(mid -0.249642 -0.249642)
							(end -0.2794 -0.1778)
						)
						(arc
							(start -0.2794 0.1778)
							(mid -0.249642 0.249642)
							(end -0.1778 0.2794)
						)
						(arc
							(start 0.1778 0.2794)
							(mid 0.249642 0.249642)
							(end 0.2794 0.1778)
						)
						(arc
							(start 0.2794 -0.1778)
							(mid 0.249642 -0.249642)
							(end 0.1778 -0.2794)
						)
					)
					(width 0)
					(fill yes)
				)
			)
		)
	)
	(footprint ""
		(layer "F.Cu")
		(at 479.340926 -304.462942 180)
		(property "Reference" "C190"
			(at 0 0 180)
			(layer "F.SilkS")
			(hide yes)
			(effects
				(font
					(size 1.27 1.27)
				)
			)
		)
		(property "Value" "SC1U25V3KX-GP"
			(at 0 -2.8194 180)
			(unlocked yes)
			(layer "F.Fab")
			(hide yes)
			(effects
				(font
					(size 1.016 1.016)
					(thickness 0.1524)
				)
			)
		)
		(property "Device Type" "C603H36"
			(at 0 -4.3434 180)
			(unlocked yes)
			(layer "F.Fab")
			(hide yes)
			(effects
				(font
					(size 1.016 1.016)
					(thickness 0.1524)
				)
			)
		)
		(duplicate_pad_numbers_are_jumpers no)
		(fp_line
			(start 0.508 0)
			(end -0.508 0)
			(stroke
				(width 0.2032)
				(type default)
			)
			(layer "F.SilkS")
		)
		(fp_rect
			(start -0.5842 1.3335)
			(end 0.5842 -1.3335)
			(stroke
				(width 0)
				(type default)
			)
			(fill no)
			(layer "F.CrtYd")
		)
		(fp_rect
			(start -0.5842 1.3335)
			(end 0.5842 -1.3335)
			(stroke
				(width 0)
				(type default)
			)
			(fill no)
			(layer "F.Fab")
		)
		(pad "1" smd custom
			(at 0 -0.762 180)
			(size 0.2159 0.2159)
			(layers "F.Cu" "F.Mask" "F.Paste")
			(net "P12V_HDD11")
			(options
				(clearance outline)
				(anchor circle)
			)
			(primitives
				(gr_poly
					(pts
						(arc
							(start -0.3302 -0.4318)
							(mid -0.402042 -0.402042)
							(end -0.4318 -0.3302)
						)
						(arc
							(start -0.4318 0.3302)
							(mid -0.402042 0.402042)
							(end -0.3302 0.4318)
						)
						(arc
							(start 0.3302 0.4318)
							(mid 0.402042 0.402042)
							(end 0.4318 0.3302)
						)
						(arc
							(start 0.4318 -0.3302)
							(mid 0.402042 -0.402042)
							(end 0.3302 -0.4318)
						)
					)
					(width 0)
					(fill yes)
				)
			)
		)
		(pad "2" smd custom
			(at 0 0.762 180)
			(size 0.2159 0.2159)
			(layers "F.Cu" "F.Mask" "F.Paste")
			(net "GND")
			(options
				(clearance outline)
				(anchor circle)
			)
			(primitives
				(gr_poly
					(pts
						(arc
							(start -0.3302 -0.4318)
							(mid -0.402042 -0.402042)
							(end -0.4318 -0.3302)
						)
						(arc
							(start -0.4318 0.3302)
							(mid -0.402042 0.402042)
							(end -0.3302 0.4318)
						)
						(arc
							(start 0.3302 0.4318)
							(mid 0.402042 0.402042)
							(end 0.4318 0.3302)
						)
						(arc
							(start 0.4318 -0.3302)
							(mid 0.402042 -0.402042)
							(end 0.3302 -0.4318)
						)
					)
					(width 0)
					(fill yes)
				)
			)
		)
	)
	(footprint ""
		(layer "F.Cu")
		(at 146.247866 -145.372074 180)
		(property "Reference" "C548"
			(at 0 0 180)
			(layer "F.SilkS")
			(hide yes)
			(effects
				(font
					(size 1.27 1.27)
				)
			)
		)
		(property "Value" "SCD1U25V2KX-2-GP"
			(at 1.1811 -2.7051 180)
			(unlocked yes)
			(layer "F.Fab")
			(hide yes)
			(effects
				(font
					(size 1.016 1.016)
					(thickness 0.1524)
				)
			)
		)
		(property "Device Type" "C402H22"
			(at 1.1811 -4.2291 180)
			(unlocked yes)
			(layer "F.Fab")
			(hide yes)
			(effects
				(font
					(size 1.016 1.016)
					(thickness 0.1524)
				)
			)
		)
		(duplicate_pad_numbers_are_jumpers no)
		(fp_rect
			(start -0.4318 0.9525)
			(end 0.4318 -0.9525)
			(stroke
				(width 0)
				(type default)
			)
			(fill no)
			(layer "F.CrtYd")
		)
		(fp_rect
			(start -0.4318 0.9525)
			(end 0.4318 -0.9525)
			(stroke
				(width 0)
				(type default)
			)
			(fill no)
			(layer "F.Fab")
		)
		(pad "1" smd custom
			(at 0 -0.4445 180)
			(size 0.1524 0.1524)
			(layers "F.Cu" "F.Mask" "F.Paste")
			(net "MB0_ISET_R")
			(options
				(clearance outline)
				(anchor circle)
			)
			(primitives
				(gr_poly
					(pts
						(arc
							(start 0.3048 -0.2032)
							(mid 0.275042 -0.275042)
							(end 0.2032 -0.3048)
						)
						(arc
							(start -0.2032 -0.3048)
							(mid -0.275042 -0.275042)
							(end -0.3048 -0.2032)
						)
						(arc
							(start -0.3048 0.2032)
							(mid -0.275042 0.275042)
							(end -0.2032 0.3048)
						)
						(arc
							(start 0.2032 0.3048)
							(mid 0.275042 0.275042)
							(end 0.3048 0.2032)
						)
					)
					(width 0)
					(fill yes)
				)
			)
		)
		(pad "2" smd custom
			(at 0 0.4445 180)
			(size 0.1524 0.1524)
			(layers "F.Cu" "F.Mask" "F.Paste")
			(net "AGND_CURRENT_MONOA")
			(options
				(clearance outline)
				(anchor circle)
			)
			(primitives
				(gr_poly
					(pts
						(arc
							(start 0.3048 -0.2032)
							(mid 0.275042 -0.275042)
							(end 0.2032 -0.3048)
						)
						(arc
							(start -0.2032 -0.3048)
							(mid -0.275042 -0.275042)
							(end -0.3048 -0.2032)
						)
						(arc
							(start -0.3048 0.2032)
							(mid -0.275042 0.275042)
							(end -0.2032 0.3048)
						)
						(arc
							(start 0.2032 0.3048)
							(mid 0.275042 0.275042)
							(end 0.3048 0.2032)
						)
					)
					(width 0)
					(fill yes)
				)
			)
		)
	)
	(footprint ""
		(layer "F.Cu")
		(at 319.151 -177.2539 -90)
		(property "Reference" "R544"
			(at 0 0 270)
			(layer "F.SilkS")
			(hide yes)
			(effects
				(font
					(size 1.27 1.27)
				)
			)
		)
		(property "Value" "10KR2F-2-GP"
			(at 0.064008 -3.993896 270)
			(unlocked yes)
			(layer "F.Fab")
			(hide yes)
			(effects
				(font
					(size 1.016 1.016)
					(thickness 0.1524)
				)
			)
		)
		(property "Device Type" "R402H16"
			(at 0.064008 -5.517896 270)
			(unlocked yes)
			(layer "F.Fab")
			(hide yes)
			(effects
				(font
					(size 1.016 1.016)
					(thickness 0.1524)
				)
			)
		)
		(duplicate_pad_numbers_are_jumpers no)
		(fp_line
			(start -0.508 -0.9398)
			(end -0.508 0.9398)
			(stroke
				(width 0.1524)
				(type default)
			)
			(layer "F.SilkS")
		)
		(fp_line
			(start 0.508 -0.9398)
			(end -0.508 -0.9398)
			(stroke
				(width 0.1524)
				(type default)
			)
			(layer "F.SilkS")
		)
		(fp_rect
			(start -0.508 0.9398)
			(end 0.508 -0.9398)
			(stroke
				(width 0)
				(type default)
			)
			(fill no)
			(layer "F.CrtYd")
		)
		(fp_rect
			(start -0.508 0.9398)
			(end 0.508 -0.9398)
			(stroke
				(width 0)
				(type default)
			)
			(fill no)
			(layer "F.Fab")
		)
		(pad "1" smd custom
			(at 0 -0.4445 270)
			(size 0.1397 0.1397)
			(layers "F.Cu" "F.Mask" "F.Paste")
			(net "P3V3_STBY_A")
			(options
				(clearance outline)
				(anchor circle)
			)
			(primitives
				(gr_poly
					(pts
						(arc
							(start -0.1778 -0.2794)
							(mid -0.249642 -0.249642)
							(end -0.2794 -0.1778)
						)
						(arc
							(start -0.2794 0.1778)
							(mid -0.249642 0.249642)
							(end -0.1778 0.2794)
						)
						(arc
							(start 0.1778 0.2794)
							(mid 0.249642 0.249642)
							(end 0.2794 0.1778)
						)
						(arc
							(start 0.2794 -0.1778)
							(mid 0.249642 -0.249642)
							(end 0.1778 -0.2794)
						)
					)
					(width 0)
					(fill yes)
				)
			)
		)
		(pad "2" smd custom
			(at 0 0.4445 270)
			(size 0.1397 0.1397)
			(layers "F.Cu" "F.Mask" "F.Paste")
			(net "HDD_PRSNT_18")
			(options
				(clearance outline)
				(anchor circle)
			)
			(primitives
				(gr_poly
					(pts
						(arc
							(start -0.1778 -0.2794)
							(mid -0.249642 -0.249642)
							(end -0.2794 -0.1778)
						)
						(arc
							(start -0.2794 0.1778)
							(mid -0.249642 0.249642)
							(end -0.1778 0.2794)
						)
						(arc
							(start 0.1778 0.2794)
							(mid 0.249642 0.249642)
							(end 0.2794 0.1778)
						)
						(arc
							(start 0.2794 -0.1778)
							(mid 0.249642 -0.249642)
							(end 0.1778 -0.2794)
						)
					)
					(width 0)
					(fill yes)
				)
			)
		)
	)
	(footprint ""
		(layer "F.Cu")
		(at 223.88068 -342.566752 180)
		(property "Reference" "R158"
			(at 0 0 180)
			(layer "F.SilkS")
			(hide yes)
			(effects
				(font
					(size 1.27 1.27)
				)
			)
		)
		(property "Value" "4K7R2F-GP"
			(at 0.064008 -3.993896 180)
			(unlocked yes)
			(layer "F.Fab")
			(hide yes)
			(effects
				(font
					(size 1.016 1.016)
					(thickness 0.1524)
				)
			)
		)
		(property "Device Type" "R402H16"
			(at 0.064008 -5.517896 180)
			(unlocked yes)
			(layer "F.Fab")
			(hide yes)
			(effects
				(font
					(size 1.016 1.016)
					(thickness 0.1524)
				)
			)
		)
		(duplicate_pad_numbers_are_jumpers no)
		(fp_line
			(start 0.508 -0.9398)
			(end -0.508 -0.9398)
			(stroke
				(width 0.1524)
				(type default)
			)
			(layer "F.SilkS")
		)
		(fp_line
			(start -0.508 -0.9398)
			(end -0.508 0.9398)
			(stroke
				(width 0.1524)
				(type default)
			)
			(layer "F.SilkS")
		)
		(fp_rect
			(start -0.508 0.9398)
			(end 0.508 -0.9398)
			(stroke
				(width 0)
				(type default)
			)
			(fill no)
			(layer "F.CrtYd")
		)
		(fp_rect
			(start -0.508 0.9398)
			(end 0.508 -0.9398)
			(stroke
				(width 0)
				(type default)
			)
			(fill no)
			(layer "F.Fab")
		)
		(pad "1" smd custom
			(at 0 -0.4445 180)
			(size 0.1397 0.1397)
			(layers "F.Cu" "F.Mask" "F.Paste")
			(net "VOL_SEN_ADDR1")
			(options
				(clearance outline)
				(anchor circle)
			)
			(primitives
				(gr_poly
					(pts
						(arc
							(start -0.1778 -0.2794)
							(mid -0.249642 -0.249642)
							(end -0.2794 -0.1778)
						)
						(arc
							(start -0.2794 0.1778)
							(mid -0.249642 0.249642)
							(end -0.1778 0.2794)
						)
						(arc
							(start 0.1778 0.2794)
							(mid 0.249642 0.249642)
							(end 0.2794 0.1778)
						)
						(arc
							(start 0.2794 -0.1778)
							(mid 0.249642 -0.249642)
							(end 0.1778 -0.2794)
						)
					)
					(width 0)
					(fill yes)
				)
			)
		)
		(pad "2" smd custom
			(at 0 0.4445 180)
			(size 0.1397 0.1397)
			(layers "F.Cu" "F.Mask" "F.Paste")
			(net "GND")
			(options
				(clearance outline)
				(anchor circle)
			)
			(primitives
				(gr_poly
					(pts
						(arc
							(start -0.1778 -0.2794)
							(mid -0.249642 -0.249642)
							(end -0.2794 -0.1778)
						)
						(arc
							(start -0.2794 0.1778)
							(mid -0.249642 0.249642)
							(end -0.1778 0.2794)
						)
						(arc
							(start 0.1778 0.2794)
							(mid 0.249642 0.249642)
							(end 0.2794 0.1778)
						)
						(arc
							(start 0.2794 -0.1778)
							(mid 0.249642 -0.249642)
							(end 0.1778 -0.2794)
						)
					)
					(width 0)
					(fill yes)
				)
			)
		)
	)
)
